(kicad_pcb
	(version 20241229)
	(generator "pcbnew")
	(generator_version "9.0")
	(general
		(thickness 1.6296)
		(legacy_teardrops no)
	)
	(paper "A3")
	(title_block
		(title "Thunderbolt to 10GbE adapter")
		(date "2026-04-21")
		(rev "1.1.0")
		(company "Antmicro Ltd")
		(comment 1 "www.antmicro.com")
		(comment 9 "footprint 4 of 703 (U4), pads 328-337 of 337")
	)
	(layers
		(0 "F.Cu" signal)
		(4 "In1.Cu" signal)
		(6 "In2.Cu" signal)
		(8 "In3.Cu" signal)
		(10 "In4.Cu" signal)
		(12 "In5.Cu" signal)
		(14 "In6.Cu" signal)
		(2 "B.Cu" signal)
		(9 "F.Adhes" user "F.Adhesive")
		(11 "B.Adhes" user "B.Adhesive")
		(13 "F.Paste" user)
		(15 "B.Paste" user)
		(5 "F.SilkS" user "F.Silkscreen")
		(7 "B.SilkS" user "B.Silkscreen")
		(1 "F.Mask" user)
		(3 "B.Mask" user)
		(17 "Dwgs.User" user "User.Drawings")
		(19 "Cmts.User" user "User.Comments")
		(21 "Eco1.User" user "User.Eco1")
		(23 "Eco2.User" user "User.Eco2")
		(25 "Edge.Cuts" user)
		(27 "Margin" user)
		(31 "F.CrtYd" user "F.Courtyard")
		(29 "B.CrtYd" user "B.Courtyard")
		(35 "F.Fab" user)
		(33 "B.Fab" user)
	)
	(footprint "antmicro-footprints:JHL6340SLLSQ"
		(layer "F.Cu")
		(at 128.5 123.95 180)
		(property "Reference" "U4"
			(at 4.9 6.15 0)
			(unlocked yes)
			(layer "F.SilkS")
			(effects
				(font
					(size 0.7 0.7)
					(thickness 0.15)
				)
			)
		)
		(property "Value" "JHL6340SLLSQ"
			(at 0 6.4 180)
			(unlocked yes)
			(layer "F.Fab")
			(effects
				(font
					(size 0.7 0.7)
					(thickness 0.15)
				)
			)
		)
		(property "Datasheet" "https://www.thunderbolttechnology.net/sites/default/files/18-241_ThunderboltController_Brief_HI.pdf"
			(at 0 0 180)
			(layer "F.Fab")
			(hide yes)
			(effects
				(font
					(size 1.27 1.27)
					(thickness 0.15)
				)
			)
		)
		(property "Description" "Thunderbolt™ 3 Controller, I/O"
			(at 0 0 180)
			(layer "F.Fab")
			(hide yes)
			(effects
				(font
					(size 1.27 1.27)
					(thickness 0.15)
				)
			)
		)
		(property "Manufacturer" "Intel"
			(at 0 0 180)
			(unlocked yes)
			(layer "F.Fab")
			(hide yes)
			(effects
				(font
					(size 1 1)
					(thickness 0.15)
				)
			)
		)
		(property "MPN" "JHL6340SLLSQ"
			(at 0 0 180)
			(unlocked yes)
			(layer "F.Fab")
			(hide yes)
			(effects
				(font
					(size 1 1)
					(thickness 0.15)
				)
			)
		)
		(property "Author" "Antmicro"
			(at 0 0 180)
			(unlocked yes)
			(layer "F.Fab")
			(hide yes)
			(effects
				(font
					(size 1 1)
					(thickness 0.15)
				)
			)
		)
		(property "License" "Apache-2.0"
			(at 0 0 180)
			(unlocked yes)
			(layer "F.Fab")
			(hide yes)
			(effects
				(font
					(size 1 1)
					(thickness 0.15)
				)
			)
		)
		(sheetname "/TB Controller/")
		(sheetfile "tb.kicad_sch")
		(attr smd)
		(pad "Y11" smd circle
			(at -0.65 3.9 180)
			(size 0.254 0.254)
			(layers "F.Cu" "F.Mask" "F.Paste")
			(net 286 "unconnected-(U4C-DPSNK0_AUXP-PadY11)")
			(pinfunction "DPSNK0_AUXP")
			(pintype "bidirectional+no_connect")
		)
		(pad "Y12" smd circle
			(at 0 3.9 180)
			(size 0.254 0.254)
			(layers "F.Cu" "F.Mask" "F.Paste")
			(net 287 "unconnected-(U4C-DPSNK1_AUXP-PadY12)")
			(pinfunction "DPSNK1_AUXP")
			(pintype "bidirectional+no_connect")
		)
		(pad "Y13" smd circle
			(at 0.65 3.9 180)
			(size 0.254 0.254)
			(layers "F.Cu" "F.Mask" "F.Paste")
			(net 23 "GND")
			(pinfunction "VSS_ANA")
			(pintype "passive")
		)
		(pad "Y15" smd circle
			(at 1.3 3.9 180)
			(size 0.254 0.254)
			(layers "F.Cu" "F.Mask" "F.Paste")
			(net 239 "/TB Controller/PA_AUX_P")
			(pinfunction "PA_DPSRC_AUX_P")
			(pintype "bidirectional")
		)
		(pad "Y16" smd circle
			(at 1.95 3.9 180)
			(size 0.254 0.254)
			(layers "F.Cu" "F.Mask" "F.Paste")
			(net 288 "unconnected-(U4E-PB_DPSRC_AUX_P-PadY16)")
			(pinfunction "PB_DPSRC_AUX_P")
			(pintype "bidirectional+no_connect")
		)
		(pad "Y18" smd circle
			(at 2.6 3.9 180)
			(size 0.254 0.254)
			(layers "F.Cu" "F.Mask" "F.Paste")
			(net 223 "Net-(U4C-DPSNK_RBIAS)")
			(pinfunction "DPSNK_RBIAS")
			(pintype "passive")
		)
		(pad "Y19" smd circle
			(at 3.25 3.9 180)
			(size 0.254 0.254)
			(layers "F.Cu" "F.Mask" "F.Paste")
			(net 289 "unconnected-(U4C-DPSRC_AUX_N-PadY19)")
			(pinfunction "DPSRC_AUX_N")
			(pintype "bidirectional+no_connect")
		)
		(pad "Y20" smd circle
			(at 3.9 3.9 180)
			(size 0.254 0.254)
			(layers "F.Cu" "F.Mask" "F.Paste")
			(net 23 "GND")
			(pinfunction "VSS_ANA")
			(pintype "passive")
		)
		(pad "Y22" smd circle
			(at 4.6 3.68 180)
			(size 0.254 0.254)
			(layers "F.Cu" "F.Mask" "F.Paste")
			(net 597 "/TB Controller/PCIex4.TX0-")
			(pinfunction "PCIE_RX0_N")
			(pintype "input")
		)
		(pad "Y23" smd oval
			(at 5.06 3.68 270)
			(size 0.1578 0.3302)
			(layers "F.Cu" "F.Mask" "F.Paste")
			(net 596 "/TB Controller/PCIex4.TX0+")
			(pinfunction "PCIE_RX0_P")
			(pintype "input")
		)
	)
)
